# S9S_MB_2U (Grand Teton) — schematic netlist excerpt (pin names and nets, part order shuffled) for the footprints in the layout excerpt that follows; sources: Cadence DE-HDL packaged netlist, KiCad conversion of 03242023_DA0F0TMBIJ0_F0T_Motherboard_J_brd_V01_OCP.brd

C2374  Q_CAP  1000PF 50V 5% EMPTY  pkg 0402  page 144 : A = PRSNT_CABLE_SWB_B1_ISO_N ; B = GND

U329  MOSFET_NCH_GDS_ESD_PROTECTED  2N7002K EMPTY  pkg SOT23_GDSXC  page 306
  D  = A_HSC_LOW_DRAIN
  G  = A_HSC_LOW_GATE
  S  = GND

(kicad_pcb
	(version 20260206)
	(generator "pcbnew")
	(generator_version "10.0")
	(general
		(thickness 1.6)
		(legacy_teardrops no)
	)
	(paper "A4")
	(title_block
		(title "03242023_DA0F0TMBIJ0_F0T_Motherboard_J_brd_V01_OCP.brd")
		(comment 1 "Grand Teton / footprints 1026-1027 of 6105")
	)
	(layers
		(0 "F.Cu" signal "TOP")
		(4 "In1.Cu" signal "GND")
		(6 "In2.Cu" signal "IN1")
		(8 "In3.Cu" signal "GND1")
		(10 "In4.Cu" signal "IN2")
		(12 "In5.Cu" signal "GND2")
		(14 "In6.Cu" signal "IN3")
		(16 "In7.Cu" signal "GND3")
		(18 "In8.Cu" signal "VCC")
		(20 "In9.Cu" signal "VCC1")
		(22 "In10.Cu" signal "GND4")
		(24 "In11.Cu" signal "IN4")
		(26 "In12.Cu" signal "GND5")
		(28 "In13.Cu" signal "IN5")
		(30 "In14.Cu" signal "GND6")
		(32 "In15.Cu" signal "IN6")
		(34 "In16.Cu" signal "GND7")
		(2 "B.Cu" signal "BOTTOM")
		(9 "F.Adhes" user "F.Adhesive")
		(11 "B.Adhes" user "B.Adhesive")
		(13 "F.Paste" user "Package Geometry/Pastemask Top")
		(15 "B.Paste" user "Package Geometry/Pastemask Bottom")
		(5 "F.SilkS" user "Ref Des/Silkscreen Top")
		(7 "B.SilkS" user "Ref Des/Silkscreen Bottom")
		(1 "F.Mask" user "Board Geometry/Soldermask Top")
		(3 "B.Mask" user "Board Geometry/Soldermask Bottom")
		(17 "Dwgs.User" user "User.Drawings")
		(19 "Cmts.User" user "User.Comments")
		(21 "Eco1.User" user "User.Eco1")
		(23 "Eco2.User" user "User.Eco2")
		(25 "Edge.Cuts" user "Board Geometry/Outline")
		(27 "Margin" user)
		(31 "F.CrtYd" user "Package Geometry/Place Bound Top")
		(29 "B.CrtYd" user "Package Geometry/Place Bound Bottom")
		(35 "F.Fab" user "Ref Des/Assembly Top")
		(33 "B.Fab" user "Ref Des/Assembly Bottom")
	)
	(footprint ""
		(layer "F.Cu")
		(at 366.3696 -405.9936 180)
		(property "Reference" "C2374"
			(at 0 0 180)
			(layer "F.SilkS")
			(hide yes)
			(effects
				(font
					(size 1.27 1.27)
				)
			)
		)
		(property "Value" ""
			(at 0 0 180)
			(layer "F.Fab")
			(effects
				(font
					(size 1.27 1.27)
				)
			)
		)
		(duplicate_pad_numbers_are_jumpers no)
		(fp_line
			(start 0.7874 0.4064)
			(end -0.7874 0.4064)
			(stroke
				(width 0.1524)
				(type default)
			)
			(layer "F.SilkS")
		)
		(fp_line
			(start 0.7874 -0.4064)
			(end 0.7874 0.4064)
			(stroke
				(width 0.1524)
				(type default)
			)
			(layer "F.SilkS")
		)
		(fp_line
			(start -0.7874 0.4064)
			(end -0.7874 -0.4064)
			(stroke
				(width 0.1524)
				(type default)
			)
			(layer "F.SilkS")
		)
		(fp_line
			(start -0.7874 -0.4064)
			(end 0.7874 -0.4064)
			(stroke
				(width 0.1524)
				(type default)
			)
			(layer "F.SilkS")
		)
		(fp_line
			(start 0.67945 0.3048)
			(end 0.120396 0.3048)
			(stroke
				(width 0.1)
				(type default)
			)
			(layer "F.Fab")
		)
		(fp_line
			(start 0.67945 -0.3048)
			(end 0.67945 0.3048)
			(stroke
				(width 0.1)
				(type default)
			)
			(layer "F.Fab")
		)
		(fp_line
			(start 0.12065 -0.2794)
			(end 0.12065 -0.3048)
			(stroke
				(width 0.1)
				(type default)
			)
			(layer "F.Fab")
		)
		(fp_line
			(start 0.12065 -0.3048)
			(end 0.67945 -0.3048)
			(stroke
				(width 0.1)
				(type default)
			)
			(layer "F.Fab")
		)
		(fp_line
			(start 0.120396 0.3048)
			(end 0.120396 0.2794)
			(stroke
				(width 0.1)
				(type default)
			)
			(layer "F.Fab")
		)
		(fp_line
			(start 0.120396 0.2794)
			(end -0.12065 0.2794)
			(stroke
				(width 0.1)
				(type default)
			)
			(layer "F.Fab")
		)
		(fp_line
			(start -0.12065 0.3048)
			(end -0.67945 0.3048)
			(stroke
				(width 0.1)
				(type default)
			)
			(layer "F.Fab")
		)
		(fp_line
			(start -0.12065 0.2794)
			(end -0.12065 0.3048)
			(stroke
				(width 0.1)
				(type default)
			)
			(layer "F.Fab")
		)
		(fp_line
			(start -0.12065 -0.2794)
			(end 0.12065 -0.2794)
			(stroke
				(width 0.1)
				(type default)
			)
			(layer "F.Fab")
		)
		(fp_line
			(start -0.12065 -0.305054)
			(end -0.12065 -0.2794)
			(stroke
				(width 0.1)
				(type default)
			)
			(layer "F.Fab")
		)
		(fp_line
			(start -0.67945 0.3048)
			(end -0.67945 -0.305054)
			(stroke
				(width 0.1)
				(type default)
			)
			(layer "F.Fab")
		)
		(fp_line
			(start -0.67945 -0.305054)
			(end -0.12065 -0.305054)
			(stroke
				(width 0.1)
				(type default)
			)
			(layer "F.Fab")
		)
		(pad "1" smd circle
			(at -0.40005 0 180)
			(size 0 0)
			(layers "F.Cu" "F.Mask" "F.Paste")
			(net "PRSNT_CABLE_SWB_B1_ISO_N")
		)
		(pad "2" smd circle
			(at 0.40005 0 180)
			(size 0 0)
			(layers "F.Cu" "F.Mask" "F.Paste")
			(net "GND")
		)
	)
	(footprint ""
		(layer "F.Cu")
		(at 274.436078 -420.1033 180)
		(property "Reference" "U329"
			(at 2.276856 -2.56921 0)
			(unlocked yes)
			(layer "F.SilkS")
			(effects
				(font
					(size 0.7874 0.5842)
					(thickness 0.1524)
				)
				(justify left)
			)
		)
		(property "Value" ""
			(at 0 0 180)
			(layer "F.Fab")
			(effects
				(font
					(size 1.27 1.27)
				)
			)
		)
		(duplicate_pad_numbers_are_jumpers no)
		(fp_line
			(start 1.603248 1.500124)
			(end -1.603248 1.500124)
			(stroke
				(width 0.1524)
				(type default)
			)
			(layer "F.SilkS")
		)
		(fp_line
			(start 1.603248 -1.500124)
			(end 1.603248 1.500124)
			(stroke
				(width 0.1524)
				(type default)
			)
			(layer "F.SilkS")
		)
		(fp_line
			(start -1.603248 1.500124)
			(end -1.603248 -1.500124)
			(stroke
				(width 0.1524)
				(type default)
			)
			(layer "F.SilkS")
		)
		(fp_line
			(start -1.603248 -1.500124)
			(end 1.603248 -1.500124)
			(stroke
				(width 0.1524)
				(type default)
			)
			(layer "F.SilkS")
		)
		(fp_line
			(start 1.249934 0.219964)
			(end 1.249934 -0.219964)
			(stroke
				(width 0.1)
				(type default)
			)
			(layer "F.Fab")
		)
		(fp_line
			(start 1.249934 -0.219964)
			(end 0.700024 -0.219964)
			(stroke
				(width 0.1)
				(type default)
			)
			(layer "F.Fab")
		)
		(fp_line
			(start 0.700024 1.500124)
			(end 0.700024 0.219964)
			(stroke
				(width 0.1)
				(type default)
			)
			(layer "F.Fab")
		)
		(fp_line
			(start 0.700024 0.219964)
			(end 1.249934 0.219964)
			(stroke
				(width 0.1)
				(type default)
			)
			(layer "F.Fab")
		)
		(fp_line
			(start 0.700024 -0.219964)
			(end 0.700024 -1.500124)
			(stroke
				(width 0.1)
				(type default)
			)
			(layer "F.Fab")
		)
		(fp_line
			(start 0.700024 -1.500124)
			(end -0.700024 -1.500124)
			(stroke
				(width 0.1)
				(type default)
			)
			(layer "F.Fab")
		)
		(fp_line
			(start -0.6985 0.729996)
			(end -1.249934 0.729996)
			(stroke
				(width 0.1)
				(type default)
			)
			(layer "F.Fab")
		)
		(fp_line
			(start -0.6985 -0.729996)
			(end -0.6985 0.729996)
			(stroke
				(width 0.1)
				(type default)
			)
			(layer "F.Fab")
		)
		(fp_line
			(start -0.700024 1.500124)
			(end 0.700024 1.500124)
			(stroke
				(width 0.1)
				(type default)
			)
			(layer "F.Fab")
		)
		(fp_line
			(start -0.700024 1.169924)
			(end -0.700024 1.500124)
			(stroke
				(width 0.1)
				(type default)
			)
			(layer "F.Fab")
		)
		(fp_line
			(start -0.700024 -1.169924)
			(end -1.249934 -1.169924)
			(stroke
				(width 0.1)
				(type default)
			)
			(layer "F.Fab")
		)
		(fp_line
			(start -0.700024 -1.500124)
			(end -0.700024 -1.169924)
			(stroke
				(width 0.1)
				(type default)
			)
			(layer "F.Fab")
		)
		(fp_line
			(start -1.249934 1.169924)
			(end -0.700024 1.169924)
			(stroke
				(width 0.1)
				(type default)
			)
			(layer "F.Fab")
		)
		(fp_line
			(start -1.249934 0.729996)
			(end -1.249934 1.169924)
			(stroke
				(width 0.1)
				(type default)
			)
			(layer "F.Fab")
		)
		(fp_line
			(start -1.249934 -0.729996)
			(end -0.6985 -0.729996)
			(stroke
				(width 0.1)
				(type default)
			)
			(layer "F.Fab")
		)
		(fp_line
			(start -1.249934 -1.169924)
			(end -1.249934 -0.729996)
			(stroke
				(width 0.1)
				(type default)
			)
			(layer "F.Fab")
		)
		(fp_rect
			(start -0.700024 1.500124)
			(end 0.700024 -1.500124)
			(stroke
				(width 0)
				(type default)
			)
			(fill no)
			(layer "F.Fab")
		)
		(pad "D" smd rect
			(at 0.999998 0 90)
			(size 0.8128 0.9144)
			(layers "F.Cu" "F.Mask" "F.Paste")
			(net "A_HSC_LOW_DRAIN")
		)
		(pad "G" smd rect
			(at -0.999998 -0.94996 90)
			(size 0.8128 0.9144)
			(layers "F.Cu" "F.Mask" "F.Paste")
			(net "A_HSC_LOW_GATE")
		)
		(pad "S" smd rect
			(at -0.999998 0.94996 90)
			(size 0.8128 0.9144)
			(layers "F.Cu" "F.Mask" "F.Paste")
			(net "GND")
		)
	)
)
